(kicad_pcb
	(version 20241229)
	(generator "pcbnew")
	(generator_version "9.0")
	(general
		(thickness 1.61)
		(legacy_teardrops no)
	)
	(paper "A3")
	(title_block
		(title "SO-DIMM DDR5 Tester")
		(date "2025-11-26")
		(rev "1.3.0")
		(comment 9 "footprints 109-114 of 627")
	)
	(layers
		(0 "F.Cu" signal)
		(4 "In1.Cu" power)
		(6 "In2.Cu" mixed)
		(8 "In3.Cu" power)
		(10 "In4.Cu" mixed)
		(12 "In5.Cu" power)
		(14 "In6.Cu" mixed)
		(16 "In7.Cu" power)
		(18 "In8.Cu" power)
		(20 "In9.Cu" mixed)
		(22 "In10.Cu" power)
		(2 "B.Cu" signal)
		(9 "F.Adhes" user "F.Adhesive")
		(11 "B.Adhes" user "B.Adhesive")
		(13 "F.Paste" user)
		(15 "B.Paste" user)
		(5 "F.SilkS" user "F.Silkscreen")
		(7 "B.SilkS" user "B.Silkscreen")
		(1 "F.Mask" user)
		(3 "B.Mask" user)
		(17 "Dwgs.User" user "User.Drawings")
		(19 "Cmts.User" user "User.Comments")
		(21 "Eco1.User" user "User.Eco1")
		(23 "Eco2.User" user "User.Eco2")
		(25 "Edge.Cuts" user)
		(27 "Margin" user)
		(31 "F.CrtYd" user "F.Courtyard")
		(29 "B.CrtYd" user "B.Courtyard")
		(35 "F.Fab" user)
		(33 "B.Fab" user)
	)
	(footprint "antmicro-footprints:C_0402_1005Metric"
		(layer "F.Cu")
		(at 179.05 189.731 90)
		(descr "Capacitor SMD 0402")
		(tags "capacitor SMD 0402")
		(property "Reference" "C239"
			(at -3.9 0.5 90)
			(layer "F.SilkS")
			(effects
				(font
					(size 0.7 0.7)
					(thickness 0.15)
				)
				(justify left bottom)
			)
		)
		(property "Value" "C_100n_0402"
			(at -1.022927 2.155213 90)
			(layer "F.Fab")
			(effects
				(font
					(size 0.7 0.7)
					(thickness 0.15)
				)
				(justify left bottom)
			)
		)
		(property "Datasheet" "https://www.murata.com/products/productdetail?partno=GRM155R61H104KE14%23"
			(at 0 0 90)
			(layer "F.Fab")
			(hide yes)
			(effects
				(font
					(size 1.27 1.27)
					(thickness 0.15)
				)
			)
		)
		(property "Manufacturer" "Murata"
			(at 0 0 90)
			(unlocked yes)
			(layer "F.Fab")
			(hide yes)
			(effects
				(font
					(size 1 1)
					(thickness 0.15)
				)
			)
		)
		(property "MPN" "GRM155R61H104KE14D"
			(at 0 0 90)
			(unlocked yes)
			(layer "F.Fab")
			(hide yes)
			(effects
				(font
					(size 1 1)
					(thickness 0.15)
				)
			)
		)
		(property "Val" "100n"
			(at 0 0 90)
			(unlocked yes)
			(layer "F.Fab")
			(hide yes)
			(effects
				(font
					(size 1 1)
					(thickness 0.15)
				)
			)
		)
		(property "License" "Apache-2.0"
			(at 0 0 90)
			(unlocked yes)
			(layer "F.Fab")
			(hide yes)
			(effects
				(font
					(size 1 1)
					(thickness 0.15)
				)
			)
		)
		(property "Author" "Antmicro"
			(at 0 0 90)
			(unlocked yes)
			(layer "F.Fab")
			(hide yes)
			(effects
				(font
					(size 1 1)
					(thickness 0.15)
				)
			)
		)
		(property "Voltage" "50V"
			(at 0 0 90)
			(unlocked yes)
			(layer "F.Fab")
			(hide yes)
			(effects
				(font
					(size 1 1)
					(thickness 0.15)
				)
			)
		)
		(property "Dielectric" "X5R"
			(at 0 0 90)
			(unlocked yes)
			(layer "F.Fab")
			(hide yes)
			(effects
				(font
					(size 1 1)
					(thickness 0.15)
				)
			)
		)
		(sheetname "/I^{2}C/")
		(sheetfile "i2c.kicad_sch")
		(attr smd)
		(fp_poly
			(pts
				(xy -0.925 -0.47) (xy 0.925 -0.47) (xy 0.925 0.47) (xy -0.925 0.47)
			)
			(stroke
				(width 0.05)
				(type default)
			)
			(fill no)
			(layer "F.CrtYd")
		)
		(fp_line
			(start 0.504 -0.25)
			(end 0.504 0.248)
			(stroke
				(width 0.15)
				(type solid)
			)
			(layer "F.Fab")
		)
		(fp_line
			(start -0.494 -0.25)
			(end 0.504 -0.25)
			(stroke
				(width 0.15)
				(type solid)
			)
			(layer "F.Fab")
		)
		(fp_line
			(start 0.504 0.248)
			(end -0.494 0.248)
			(stroke
				(width 0.15)
				(type solid)
			)
			(layer "F.Fab")
		)
		(fp_line
			(start -0.494 0.248)
			(end -0.494 -0.25)
			(stroke
				(width 0.15)
				(type solid)
			)
			(layer "F.Fab")
		)
		(fp_text user "License: Apache-2.0"
			(at -0.939 5.799 90)
			(layer "F.Fab")
			(effects
				(font
					(size 0.7 0.7)
					(thickness 0.15)
				)
				(justify left bottom)
			)
		)
		(fp_text user "${REFERENCE}"
			(at -0.939 4.599 90)
			(layer "F.Fab")
			(effects
				(font
					(size 0.7 0.7)
					(thickness 0.15)
				)
				(justify left bottom)
			)
		)
		(fp_text user "Author: Antmicro"
			(at -0.939 3.399 90)
			(layer "F.Fab")
			(effects
				(font
					(size 0.7 0.7)
					(thickness 0.15)
				)
				(justify left bottom)
			)
		)
		(pad "1" smd roundrect
			(at -0.48 0 90)
			(size 0.59 0.64)
			(layers "F.Cu" "F.Mask" "F.Paste")
			(roundrect_rratio 0.25)
			(net 1 "GND")
			(pintype "passive")
		)
		(pad "2" smd roundrect
			(at 0.48 0 90)
			(size 0.59 0.64)
			(layers "F.Cu" "F.Mask" "F.Paste")
			(roundrect_rratio 0.25)
			(net 759 "Net-(D17-C)")
			(pintype "passive")
		)
	)
	(footprint "antmicro-footprints:C_0402_1005Metric"
		(layer "F.Cu")
		(at 184.15 196.65 -90)
		(descr "Capacitor SMD 0402")
		(tags "capacitor SMD 0402")
		(property "Reference" "C196"
			(at 0 -0.699 270)
			(layer "F.SilkS")
			(hide yes)
			(effects
				(font
					(size 0.7 0.7)
					(thickness 0.15)
				)
				(justify left bottom)
			)
		)
		(property "Value" "C_100n_0402"
			(at -1.022927 2.155213 270)
			(layer "F.Fab")
			(effects
				(font
					(size 0.7 0.7)
					(thickness 0.15)
				)
				(justify left bottom)
			)
		)
		(property "Datasheet" "https://www.murata.com/products/productdetail?partno=GRM155R61H104KE14%23"
			(at 0 0 270)
			(layer "F.Fab")
			(hide yes)
			(effects
				(font
					(size 1.27 1.27)
					(thickness 0.15)
				)
			)
		)
		(property "Author" "Antmicro"
			(at -12.5 380.8 0)
			(layer "F.Fab")
			(hide yes)
			(effects
				(font
					(size 1 1)
					(thickness 0.15)
				)
			)
		)
		(property "Dielectric" "X5R"
			(at -12.5 380.8 0)
			(layer "F.Fab")
			(hide yes)
			(effects
				(font
					(size 1 1)
					(thickness 0.15)
				)
			)
		)
		(property "License" "Apache-2.0"
			(at -12.5 380.8 0)
			(layer "F.Fab")
			(hide yes)
			(effects
				(font
					(size 1 1)
					(thickness 0.15)
				)
			)
		)
		(property "MPN" "GRM155R61H104KE14D"
			(at -12.5 380.8 0)
			(layer "F.Fab")
			(hide yes)
			(effects
				(font
					(size 1 1)
					(thickness 0.15)
				)
			)
		)
		(property "Manufacturer" "Murata"
			(at -12.5 380.8 0)
			(layer "F.Fab")
			(hide yes)
			(effects
				(font
					(size 1 1)
					(thickness 0.15)
				)
			)
		)
		(property "Val" "100n"
			(at -12.5 380.8 0)
			(layer "F.Fab")
			(hide yes)
			(effects
				(font
					(size 1 1)
					(thickness 0.15)
				)
			)
		)
		(property "Voltage" "50V"
			(at -12.5 380.8 0)
			(layer "F.Fab")
			(hide yes)
			(effects
				(font
					(size 1 1)
					(thickness 0.15)
				)
			)
		)
		(sheetname "/I^{2}C/")
		(sheetfile "i2c.kicad_sch")
		(attr smd)
		(fp_rect
			(start -0.9659 -0.481258)
			(end 0.9649 0.458742)
			(stroke
				(width 0.05)
				(type solid)
			)
			(fill no)
			(layer "F.CrtYd")
		)
		(fp_line
			(start -0.499 0.248)
			(end -0.499 -0.25)
			(stroke
				(width 0.15)
				(type solid)
			)
			(layer "F.Fab")
		)
		(fp_line
			(start 0.499 0.248)
			(end -0.499 0.248)
			(stroke
				(width 0.15)
				(type solid)
			)
			(layer "F.Fab")
		)
		(fp_line
			(start -0.499 -0.25)
			(end 0.499 -0.25)
			(stroke
				(width 0.15)
				(type solid)
			)
			(layer "F.Fab")
		)
		(fp_line
			(start 0.499 -0.25)
			(end 0.499 0.248)
			(stroke
				(width 0.15)
				(type solid)
			)
			(layer "F.Fab")
		)
		(pad "1" smd roundrect
			(at -0.484 0 270)
			(size 0.59 0.64)
			(layers "F.Cu" "F.Mask" "F.Paste")
			(roundrect_rratio 0.25)
			(net 1 "GND")
			(pintype "passive")
		)
		(pad "2" smd roundrect
			(at 0.484 0 270)
			(size 0.59 0.64)
			(layers "F.Cu" "F.Mask" "F.Paste")
			(roundrect_rratio 0.25)
			(net 41 "+3V3_AON")
			(pintype "passive")
		)
	)
	(footprint "antmicro-footprints:C_0402_1005Metric"
		(layer "F.Cu")
		(at 184.15 192.9 -90)
		(descr "Capacitor SMD 0402")
		(tags "capacitor SMD 0402")
		(property "Reference" "C197"
			(at 0 -0.699 270)
			(layer "F.SilkS")
			(hide yes)
			(effects
				(font
					(size 0.7 0.7)
					(thickness 0.15)
				)
				(justify left bottom)
			)
		)
		(property "Value" "C_100n_0402"
			(at -1.022927 2.155213 270)
			(layer "F.Fab")
			(effects
				(font
					(size 0.7 0.7)
					(thickness 0.15)
				)
				(justify left bottom)
			)
		)
		(property "Datasheet" "https://www.murata.com/products/productdetail?partno=GRM155R61H104KE14%23"
			(at 0 0 270)
			(layer "F.Fab")
			(hide yes)
			(effects
				(font
					(size 1.27 1.27)
					(thickness 0.15)
				)
			)
		)
		(property "Author" "Antmicro"
			(at -8.75 377.05 0)
			(layer "F.Fab")
			(hide yes)
			(effects
				(font
					(size 1 1)
					(thickness 0.15)
				)
			)
		)
		(property "Dielectric" "X5R"
			(at -8.75 377.05 0)
			(layer "F.Fab")
			(hide yes)
			(effects
				(font
					(size 1 1)
					(thickness 0.15)
				)
			)
		)
		(property "License" "Apache-2.0"
			(at -8.75 377.05 0)
			(layer "F.Fab")
			(hide yes)
			(effects
				(font
					(size 1 1)
					(thickness 0.15)
				)
			)
		)
		(property "MPN" "GRM155R61H104KE14D"
			(at -8.75 377.05 0)
			(layer "F.Fab")
			(hide yes)
			(effects
				(font
					(size 1 1)
					(thickness 0.15)
				)
			)
		)
		(property "Manufacturer" "Murata"
			(at -8.75 377.05 0)
			(layer "F.Fab")
			(hide yes)
			(effects
				(font
					(size 1 1)
					(thickness 0.15)
				)
			)
		)
		(property "Val" "100n"
			(at -8.75 377.05 0)
			(layer "F.Fab")
			(hide yes)
			(effects
				(font
					(size 1 1)
					(thickness 0.15)
				)
			)
		)
		(property "Voltage" "50V"
			(at -8.75 377.05 0)
			(layer "F.Fab")
			(hide yes)
			(effects
				(font
					(size 1 1)
					(thickness 0.15)
				)
			)
		)
		(sheetname "/I^{2}C/")
		(sheetfile "i2c.kicad_sch")
		(attr smd)
		(fp_rect
			(start -0.9659 -0.481258)
			(end 0.9649 0.458742)
			(stroke
				(width 0.05)
				(type solid)
			)
			(fill no)
			(layer "F.CrtYd")
		)
		(fp_line
			(start -0.499 0.248)
			(end -0.499 -0.25)
			(stroke
				(width 0.15)
				(type solid)
			)
			(layer "F.Fab")
		)
		(fp_line
			(start 0.499 0.248)
			(end -0.499 0.248)
			(stroke
				(width 0.15)
				(type solid)
			)
			(layer "F.Fab")
		)
		(fp_line
			(start -0.499 -0.25)
			(end 0.499 -0.25)
			(stroke
				(width 0.15)
				(type solid)
			)
			(layer "F.Fab")
		)
		(fp_line
			(start 0.499 -0.25)
			(end 0.499 0.248)
			(stroke
				(width 0.15)
				(type solid)
			)
			(layer "F.Fab")
		)
		(pad "1" smd roundrect
			(at -0.484 0 270)
			(size 0.59 0.64)
			(layers "F.Cu" "F.Mask" "F.Paste")
			(roundrect_rratio 0.25)
			(net 1 "GND")
			(pintype "passive")
		)
		(pad "2" smd roundrect
			(at 0.484 0 270)
			(size 0.59 0.64)
			(layers "F.Cu" "F.Mask" "F.Paste")
			(roundrect_rratio 0.25)
			(net 41 "+3V3_AON")
			(pintype "passive")
		)
	)
	(footprint "antmicro-footprints:NetTie-2_SMD_Pad0.127mm"
		(layer "F.Cu")
		(at 198.7 173.974998 180)
		(descr "Net tie, 2 pin, 0.127mm  SMD pads")
		(tags "net tie")
		(property "Reference" "NT16"
			(at -0.128 -1.345 180)
			(layer "F.SilkS")
			(hide yes)
			(effects
				(font
					(size 0.7 0.7)
					(thickness 0.15)
				)
				(justify left bottom)
			)
		)
		(property "Value" "Net-Tie_P0.127mm"
			(at 0 1.199 180)
			(layer "F.Fab")
			(effects
				(font
					(size 0.7 0.7)
					(thickness 0.15)
				)
				(justify left bottom)
			)
		)
		(property "Author" "Antmicro"
			(at 397.4 347.949996 0)
			(layer "F.Fab")
			(hide yes)
			(effects
				(font
					(size 1 1)
					(thickness 0.15)
				)
			)
		)
		(property "License" "Apache-2.0"
			(at 397.4 347.949996 0)
			(layer "F.Fab")
			(hide yes)
			(effects
				(font
					(size 1 1)
					(thickness 0.15)
				)
			)
		)
		(property "MPN" ""
			(at 397.4 347.949996 0)
			(layer "F.Fab")
			(hide yes)
			(effects
				(font
					(size 1 1)
					(thickness 0.15)
				)
			)
		)
		(property "Manufacturer" ""
			(at 397.4 347.949996 0)
			(layer "F.Fab")
			(hide yes)
			(effects
				(font
					(size 1 1)
					(thickness 0.15)
				)
			)
		)
		(property ki_fp_filters "Net*Tie*")
		(sheetname "/Supply/")
		(sheetfile "supply.kicad_sch")
		(attr smd exclude_from_pos_files exclude_from_bom)
		(net_tie_pad_groups "1, 2")
		(fp_poly
			(pts
				(xy -0.0635 -0.0635) (xy 0.0625 -0.0635) (xy 0.0625 0.0635) (xy -0.0635 0.0635)
			)
			(stroke
				(width 0)
				(type solid)
			)
			(fill yes)
			(layer "F.Cu")
		)
		(pad "1" smd roundrect
			(at -0.127 0)
			(size 0.127 0.127)
			(layers "F.Cu")
			(roundrect_rratio 0.5)
			(chamfer_ratio 0)
			(chamfer top_left bottom_left)
			(net 144 "/Supply/1V2_SEN_-")
			(pinfunction "1")
			(pintype "passive")
		)
		(pad "2" smd roundrect
			(at 0.126 0 180)
			(size 0.127 0.127)
			(layers "F.Cu")
			(roundrect_rratio 0.5)
			(chamfer_ratio 0)
			(chamfer top_left bottom_left)
			(net 199 "+1V2")
			(pinfunction "2")
			(pintype "passive")
		)
	)
	(footprint "antmicro-footprints:NetTie-2_SMD_Pad0.127mm"
		(layer "F.Cu")
		(at 187.875 189.101 180)
		(descr "Net tie, 2 pin, 0.127mm  SMD pads")
		(tags "net tie")
		(property "Reference" "NT9"
			(at -0.128 -1.345 180)
			(layer "F.SilkS")
			(hide yes)
			(effects
				(font
					(size 0.7 0.7)
					(thickness 0.15)
				)
				(justify left bottom)
			)
		)
		(property "Value" "Net-Tie_P0.127mm"
			(at 0 1.199 180)
			(layer "F.Fab")
			(effects
				(font
					(size 0.7 0.7)
					(thickness 0.15)
				)
				(justify left bottom)
			)
		)
		(property "Author" "Antmicro"
			(at 375.75 378.202 0)
			(layer "F.Fab")
			(hide yes)
			(effects
				(font
					(size 1 1)
					(thickness 0.15)
				)
			)
		)
		(property "License" "Apache-2.0"
			(at 375.75 378.202 0)
			(layer "F.Fab")
			(hide yes)
			(effects
				(font
					(size 1 1)
					(thickness 0.15)
				)
			)
		)
		(property "MPN" ""
			(at 375.75 378.202 0)
			(layer "F.Fab")
			(hide yes)
			(effects
				(font
					(size 1 1)
					(thickness 0.15)
				)
			)
		)
		(property "Manufacturer" ""
			(at 375.75 378.202 0)
			(layer "F.Fab")
			(hide yes)
			(effects
				(font
					(size 1 1)
					(thickness 0.15)
				)
			)
		)
		(property ki_fp_filters "Net*Tie*")
		(sheetname "/Supply/")
		(sheetfile "supply.kicad_sch")
		(attr smd exclude_from_pos_files exclude_from_bom)
		(net_tie_pad_groups "1, 2")
		(fp_poly
			(pts
				(xy -0.0635 -0.0635) (xy 0.0625 -0.0635) (xy 0.0625 0.0635) (xy -0.0635 0.0635)
			)
			(stroke
				(width 0)
				(type solid)
			)
			(fill yes)
			(layer "F.Cu")
		)
		(pad "1" smd roundrect
			(at -0.127 0)
			(size 0.127 0.127)
			(layers "F.Cu")
			(roundrect_rratio 0.5)
			(chamfer_ratio 0)
			(chamfer top_left bottom_left)
			(net 143 "/Supply/MGTAVCC_SEN_-")
			(pinfunction "1")
			(pintype "passive")
		)
		(pad "2" smd roundrect
			(at 0.126 0 180)
			(size 0.127 0.127)
			(layers "F.Cu")
			(roundrect_rratio 0.5)
			(chamfer_ratio 0)
			(chamfer top_left bottom_left)
			(net 187 "+1V0_MGTAVCC")
			(pinfunction "2")
			(pintype "passive")
		)
	)
	(footprint "antmicro-footprints:R_0402_1005Metric"
		(layer "F.Cu")
		(at 89.050501 119.926 -90)
		(descr "Resistor SMD 0402")
		(tags "resistor SMD 0402")
		(property "Reference" "R41"
			(at -1.122484 -0.772697 270)
			(layer "F.SilkS")
			(hide yes)
			(effects
				(font
					(size 0.7 0.7)
					(thickness 0.15)
				)
				(justify left bottom)
			)
		)
		(property "Value" "R_330R_0402"
			(at -1.011843 1.772047 270)
			(layer "F.Fab")
			(effects
				(font
					(size 0.7 0.7)
					(thickness 0.15)
				)
				(justify left bottom)
			)
		)
		(property "Datasheet" "https://www.bourns.com/docs/product-datasheets/cr.pdf"
			(at 0 0 270)
			(layer "F.Fab")
			(hide yes)
			(effects
				(font
					(size 1.27 1.27)
					(thickness 0.15)
				)
			)
		)
		(property "Author" "Antmicro"
			(at -30.875499 208.976501 0)
			(layer "F.Fab")
			(hide yes)
			(effects
				(font
					(size 1 1)
					(thickness 0.15)
				)
			)
		)
		(property "License" "Apache-2.0"
			(at -30.875499 208.976501 0)
			(layer "F.Fab")
			(hide yes)
			(effects
				(font
					(size 1 1)
					(thickness 0.15)
				)
			)
		)
		(property "MPN" "CR0402-FX-3300GLF"
			(at -30.875499 208.976501 0)
			(layer "F.Fab")
			(hide yes)
			(effects
				(font
					(size 1 1)
					(thickness 0.15)
				)
			)
		)
		(property "Manufacturer" "Bourns"
			(at -30.875499 208.976501 0)
			(layer "F.Fab")
			(hide yes)
			(effects
				(font
					(size 1 1)
					(thickness 0.15)
				)
			)
		)
		(property "Tolerance" "1%"
			(at -30.875499 208.976501 0)
			(layer "F.Fab")
			(hide yes)
			(effects
				(font
					(size 1 1)
					(thickness 0.15)
				)
			)
		)
		(property "Val" "330R"
			(at -30.875499 208.976501 0)
			(layer "F.Fab")
			(hide yes)
			(effects
				(font
					(size 1 1)
					(thickness 0.15)
				)
			)
		)
		(sheetname "/FPGA bank 14/")
		(sheetfile "fpga-bank-14.kicad_sch")
		(attr smd)
		(fp_rect
			(start -0.93 -0.47)
			(end 0.93 0.47)
			(stroke
				(width 0.05)
				(type solid)
			)
			(fill no)
			(layer "F.CrtYd")
		)
		(fp_rect
			(start -0.5 -0.25)
			(end 0.5 0.25)
			(stroke
				(width 0.15)
				(type solid)
			)
			(fill no)
			(layer "F.Fab")
		)
		(pad "1" smd roundrect
			(at -0.485 0 270)
			(size 0.59 0.64)
			(layers "F.Cu" "F.Mask" "F.Paste")
			(roundrect_rratio 0.25)
			(net 308 "Net-(D5-Pad2)")
			(pintype "passive")
		)
		(pad "2" smd roundrect
			(at 0.485 0 270)
			(size 0.59 0.64)
			(layers "F.Cu" "F.Mask" "F.Paste")
			(roundrect_rratio 0.25)
			(net 354 "Net-(Q5-D)")
			(pintype "passive")
		)
	)
)
